# S9S_MB_2U (Grand Teton) — schematic netlist excerpt (pin names and nets, part order shuffled) for the footprints in the layout excerpt that follows; sources: Cadence DE-HDL packaged netlist, KiCad conversion of 03242023_DA0F0TMBIJ0_F0T_Motherboard_J_brd_V01_OCP.brd

PC1175_P0_3  Q_CAP  1UF 16V 10% X6S  pkg C0402  page 272 : A = SW_P12V_PVCCFA_EHV_FIVRA_CPU0_R ; B = GND
R3590  Q_RES  33.2 1% CHIP  pkg 0402LF  page 232 : A = SMB_INA230_3V3AUX_SCL ; B = SMB_INA230_3_3V3AUX_SCL_R

(kicad_pcb
	(version 20260206)
	(generator "pcbnew")
	(generator_version "10.0")
	(general
		(thickness 1.6)
		(legacy_teardrops no)
	)
	(paper "A4")
	(title_block
		(title "03242023_DA0F0TMBIJ0_F0T_Motherboard_J_brd_V01_OCP.brd")
		(comment 1 "Grand Teton / footprints 3129-3130 of 6105")
	)
	(layers
		(0 "F.Cu" signal "TOP")
		(4 "In1.Cu" signal "GND")
		(6 "In2.Cu" signal "IN1")
		(8 "In3.Cu" signal "GND1")
		(10 "In4.Cu" signal "IN2")
		(12 "In5.Cu" signal "GND2")
		(14 "In6.Cu" signal "IN3")
		(16 "In7.Cu" signal "GND3")
		(18 "In8.Cu" signal "VCC")
		(20 "In9.Cu" signal "VCC1")
		(22 "In10.Cu" signal "GND4")
		(24 "In11.Cu" signal "IN4")
		(26 "In12.Cu" signal "GND5")
		(28 "In13.Cu" signal "IN5")
		(30 "In14.Cu" signal "GND6")
		(32 "In15.Cu" signal "IN6")
		(34 "In16.Cu" signal "GND7")
		(2 "B.Cu" signal "BOTTOM")
		(9 "F.Adhes" user "F.Adhesive")
		(11 "B.Adhes" user "B.Adhesive")
		(13 "F.Paste" user "Package Geometry/Pastemask Top")
		(15 "B.Paste" user "Package Geometry/Pastemask Bottom")
		(5 "F.SilkS" user "Ref Des/Silkscreen Top")
		(7 "B.SilkS" user "Ref Des/Silkscreen Bottom")
		(1 "F.Mask" user "Board Geometry/Soldermask Top")
		(3 "B.Mask" user "Board Geometry/Soldermask Bottom")
		(17 "Dwgs.User" user "User.Drawings")
		(19 "Cmts.User" user "User.Comments")
		(21 "Eco1.User" user "User.Eco1")
		(23 "Eco2.User" user "User.Eco2")
		(25 "Edge.Cuts" user "Board Geometry/Outline")
		(27 "Margin" user)
		(31 "F.CrtYd" user "Package Geometry/Place Bound Top")
		(29 "B.CrtYd" user "Package Geometry/Place Bound Bottom")
		(35 "F.Fab" user "Ref Des/Assembly Top")
		(33 "B.Fab" user "Ref Des/Assembly Bottom")
	)
	(footprint ""
		(layer "F.Cu")
		(at 74.2188 -35.347148 180)
		(property "Reference" "R3590"
			(at 0 0 180)
			(layer "F.SilkS")
			(hide yes)
			(effects
				(font
					(size 1.27 1.27)
				)
			)
		)
		(property "Value" ""
			(at 0 0 180)
			(layer "F.Fab")
			(effects
				(font
					(size 1.27 1.27)
				)
			)
		)
		(duplicate_pad_numbers_are_jumpers no)
		(fp_line
			(start 0.7874 0.4064)
			(end -0.7874 0.4064)
			(stroke
				(width 0.1524)
				(type default)
			)
			(layer "F.SilkS")
		)
		(fp_line
			(start 0.7874 -0.4064)
			(end 0.7874 0.4064)
			(stroke
				(width 0.1524)
				(type default)
			)
			(layer "F.SilkS")
		)
		(fp_line
			(start -0.7874 0.4064)
			(end -0.7874 -0.4064)
			(stroke
				(width 0.1524)
				(type default)
			)
			(layer "F.SilkS")
		)
		(fp_line
			(start -0.7874 -0.4064)
			(end 0.7874 -0.4064)
			(stroke
				(width 0.1524)
				(type default)
			)
			(layer "F.SilkS")
		)
		(fp_line
			(start 0.67945 0.3048)
			(end 0.120396 0.3048)
			(stroke
				(width 0.1)
				(type default)
			)
			(layer "F.Fab")
		)
		(fp_line
			(start 0.67945 -0.3048)
			(end 0.67945 0.3048)
			(stroke
				(width 0.1)
				(type default)
			)
			(layer "F.Fab")
		)
		(fp_line
			(start 0.12065 -0.2794)
			(end 0.12065 -0.3048)
			(stroke
				(width 0.1)
				(type default)
			)
			(layer "F.Fab")
		)
		(fp_line
			(start 0.12065 -0.3048)
			(end 0.67945 -0.3048)
			(stroke
				(width 0.1)
				(type default)
			)
			(layer "F.Fab")
		)
		(fp_line
			(start 0.120396 0.3048)
			(end 0.120396 0.2794)
			(stroke
				(width 0.1)
				(type default)
			)
			(layer "F.Fab")
		)
		(fp_line
			(start 0.120396 0.2794)
			(end -0.12065 0.2794)
			(stroke
				(width 0.1)
				(type default)
			)
			(layer "F.Fab")
		)
		(fp_line
			(start -0.12065 0.3048)
			(end -0.67945 0.3048)
			(stroke
				(width 0.1)
				(type default)
			)
			(layer "F.Fab")
		)
		(fp_line
			(start -0.12065 0.2794)
			(end -0.12065 0.3048)
			(stroke
				(width 0.1)
				(type default)
			)
			(layer "F.Fab")
		)
		(fp_line
			(start -0.12065 -0.2794)
			(end 0.12065 -0.2794)
			(stroke
				(width 0.1)
				(type default)
			)
			(layer "F.Fab")
		)
		(fp_line
			(start -0.12065 -0.305054)
			(end -0.12065 -0.2794)
			(stroke
				(width 0.1)
				(type default)
			)
			(layer "F.Fab")
		)
		(fp_line
			(start -0.67945 0.3048)
			(end -0.67945 -0.305054)
			(stroke
				(width 0.1)
				(type default)
			)
			(layer "F.Fab")
		)
		(fp_line
			(start -0.67945 -0.305054)
			(end -0.12065 -0.305054)
			(stroke
				(width 0.1)
				(type default)
			)
			(layer "F.Fab")
		)
		(pad "1" smd circle
			(at -0.40005 0 180)
			(size 0 0)
			(layers "F.Cu" "F.Mask" "F.Paste")
			(net "SMB_INA230_3V3AUX_SCL")
		)
		(pad "2" smd circle
			(at 0.40005 0 180)
			(size 0 0)
			(layers "F.Cu" "F.Mask" "F.Paste")
			(net "SMB_INA230_3_3V3AUX_SCL_R")
		)
	)
	(footprint ""
		(layer "F.Cu")
		(at 429.48225 -362.18368 -90)
		(property "Reference" "PC1175_P0_3"
			(at 0 0 270)
			(layer "F.SilkS")
			(hide yes)
			(effects
				(font
					(size 1.27 1.27)
				)
			)
		)
		(property "Value" ""
			(at 0 0 270)
			(layer "F.Fab")
			(effects
				(font
					(size 1.27 1.27)
				)
			)
		)
		(duplicate_pad_numbers_are_jumpers no)
		(fp_line
			(start -0.7874 0.4064)
			(end -0.7874 -0.4064)
			(stroke
				(width 0.1524)
				(type default)
			)
			(layer "F.SilkS")
		)
		(fp_line
			(start 0.7874 0.4064)
			(end -0.7874 0.4064)
			(stroke
				(width 0.1524)
				(type default)
			)
			(layer "F.SilkS")
		)
		(fp_line
			(start -0.7874 -0.4064)
			(end 0.7874 -0.4064)
			(stroke
				(width 0.1524)
				(type default)
			)
			(layer "F.SilkS")
		)
		(fp_line
			(start 0.7874 -0.4064)
			(end 0.7874 0.4064)
			(stroke
				(width 0.1524)
				(type default)
			)
			(layer "F.SilkS")
		)
		(fp_line
			(start -0.67945 0.3048)
			(end -0.67945 -0.305054)
			(stroke
				(width 0.1)
				(type default)
			)
			(layer "F.Fab")
		)
		(fp_line
			(start -0.12065 0.3048)
			(end -0.67945 0.3048)
			(stroke
				(width 0.1)
				(type default)
			)
			(layer "F.Fab")
		)
		(fp_line
			(start 0.120396 0.3048)
			(end 0.120396 0.2794)
			(stroke
				(width 0.1)
				(type default)
			)
			(layer "F.Fab")
		)
		(fp_line
			(start 0.67945 0.3048)
			(end 0.120396 0.3048)
			(stroke
				(width 0.1)
				(type default)
			)
			(layer "F.Fab")
		)
		(fp_line
			(start -0.12065 0.2794)
			(end -0.12065 0.3048)
			(stroke
				(width 0.1)
				(type default)
			)
			(layer "F.Fab")
		)
		(fp_line
			(start 0.120396 0.2794)
			(end -0.12065 0.2794)
			(stroke
				(width 0.1)
				(type default)
			)
			(layer "F.Fab")
		)
		(fp_line
			(start -0.12065 -0.2794)
			(end 0.12065 -0.2794)
			(stroke
				(width 0.1)
				(type default)
			)
			(layer "F.Fab")
		)
		(fp_line
			(start 0.12065 -0.2794)
			(end 0.12065 -0.3048)
			(stroke
				(width 0.1)
				(type default)
			)
			(layer "F.Fab")
		)
		(fp_line
			(start 0.12065 -0.3048)
			(end 0.67945 -0.3048)
			(stroke
				(width 0.1)
				(type default)
			)
			(layer "F.Fab")
		)
		(fp_line
			(start 0.67945 -0.3048)
			(end 0.67945 0.3048)
			(stroke
				(width 0.1)
				(type default)
			)
			(layer "F.Fab")
		)
		(fp_line
			(start -0.67945 -0.305054)
			(end -0.12065 -0.305054)
			(stroke
				(width 0.1)
				(type default)
			)
			(layer "F.Fab")
		)
		(fp_line
			(start -0.12065 -0.305054)
			(end -0.12065 -0.2794)
			(stroke
				(width 0.1)
				(type default)
			)
			(layer "F.Fab")
		)
		(pad "1" smd circle
			(at -0.40005 0 270)
			(size 0 0)
			(layers "F.Cu" "F.Mask" "F.Paste")
			(net "SW_P12V_PVCCFA_EHV_FIVRA_CPU0_R")
		)
		(pad "2" smd circle
			(at 0.40005 0 270)
			(size 0 0)
			(layers "F.Cu" "F.Mask" "F.Paste")
			(net "GND")
		)
	)
)
